# SCM (Grand Teton) — schematic netlist excerpt (pin names and nets, part order shuffled) for the footprints in the layout excerpt that follows; sources: Cadence DE-HDL packaged netlist, KiCad conversion of 12092022_DA0F0TMDCD0_F0T_Management_Board_D_brd_V3_OCP.brd

R483  Q_RES  33.2 1% CHIP  pkg 0402LF  page 45 : A = SPI_PCH_MUXED_IO2 ; B = SPI_PCH_IO2_FLASH_R1
R615  Q_RES  4.7K 1% EMPTY  pkg 0402LF  page 48 : A = P3V3_AUX ; B = FM_BMC_DISABLE

(kicad_pcb
	(version 20260206)
	(generator "pcbnew")
	(generator_version "10.0")
	(general
		(thickness 1.6)
		(legacy_teardrops no)
	)
	(paper "A4")
	(title_block
		(title "12092022_DA0F0TMDCD0_F0T_Management_Board_D_brd_V3_OCP.brd")
		(comment 1 "Grand Teton / footprints 513-514 of 1440")
	)
	(layers
		(0 "F.Cu" signal "TOP")
		(4 "In1.Cu" signal "GND")
		(6 "In2.Cu" signal "IN1")
		(8 "In3.Cu" signal "GND1")
		(10 "In4.Cu" signal "IN2")
		(12 "In5.Cu" signal "VCC")
		(14 "In6.Cu" signal "VCC1")
		(16 "In7.Cu" signal "IN3")
		(18 "In8.Cu" signal "GND2")
		(20 "In9.Cu" signal "IN4")
		(22 "In10.Cu" signal "GND3")
		(2 "B.Cu" signal "BOTTOM")
		(9 "F.Adhes" user "F.Adhesive")
		(11 "B.Adhes" user "B.Adhesive")
		(13 "F.Paste" user "Package Geometry/Pastemask Top")
		(15 "B.Paste" user "Package Geometry/Pastemask Bottom")
		(5 "F.SilkS" user "Ref Des/Silkscreen Top")
		(7 "B.SilkS" user "Ref Des/Silkscreen Bottom")
		(1 "F.Mask" user "Board Geometry/Soldermask Top")
		(3 "B.Mask" user "Board Geometry/Soldermask Bottom")
		(17 "Dwgs.User" user "User.Drawings")
		(19 "Cmts.User" user "User.Comments")
		(21 "Eco1.User" user "User.Eco1")
		(23 "Eco2.User" user "User.Eco2")
		(25 "Edge.Cuts" user "Board Geometry/Outline")
		(27 "Margin" user)
		(31 "F.CrtYd" user "Package Geometry/Place Bound Top")
		(29 "B.CrtYd" user "Package Geometry/Place Bound Bottom")
		(35 "F.Fab" user "Ref Des/Assembly Top")
		(33 "B.Fab" user "Ref Des/Assembly Bottom")
	)
	(footprint ""
		(layer "F.Cu")
		(at 74.168 -74.295 -90)
		(property "Reference" "R615"
			(at 0 0 270)
			(layer "F.SilkS")
			(hide yes)
			(effects
				(font
					(size 1.27 1.27)
				)
			)
		)
		(property "Value" ""
			(at 0 0 270)
			(layer "F.Fab")
			(effects
				(font
					(size 1.27 1.27)
				)
			)
		)
		(duplicate_pad_numbers_are_jumpers no)
		(fp_line
			(start -0.7874 0.4064)
			(end -0.7874 -0.4064)
			(stroke
				(width 0.1524)
				(type default)
			)
			(layer "F.SilkS")
		)
		(fp_line
			(start 0.7874 0.4064)
			(end -0.7874 0.4064)
			(stroke
				(width 0.1524)
				(type default)
			)
			(layer "F.SilkS")
		)
		(fp_line
			(start -0.7874 -0.4064)
			(end 0.7874 -0.4064)
			(stroke
				(width 0.1524)
				(type default)
			)
			(layer "F.SilkS")
		)
		(fp_line
			(start 0.7874 -0.4064)
			(end 0.7874 0.4064)
			(stroke
				(width 0.1524)
				(type default)
			)
			(layer "F.SilkS")
		)
		(fp_line
			(start -0.67945 0.3048)
			(end -0.67945 -0.305054)
			(stroke
				(width 0.1)
				(type default)
			)
			(layer "F.Fab")
		)
		(fp_line
			(start -0.12065 0.3048)
			(end -0.67945 0.3048)
			(stroke
				(width 0.1)
				(type default)
			)
			(layer "F.Fab")
		)
		(fp_line
			(start 0.120396 0.3048)
			(end 0.120396 0.2794)
			(stroke
				(width 0.1)
				(type default)
			)
			(layer "F.Fab")
		)
		(fp_line
			(start 0.67945 0.3048)
			(end 0.120396 0.3048)
			(stroke
				(width 0.1)
				(type default)
			)
			(layer "F.Fab")
		)
		(fp_line
			(start -0.12065 0.2794)
			(end -0.12065 0.3048)
			(stroke
				(width 0.1)
				(type default)
			)
			(layer "F.Fab")
		)
		(fp_line
			(start 0.120396 0.2794)
			(end -0.12065 0.2794)
			(stroke
				(width 0.1)
				(type default)
			)
			(layer "F.Fab")
		)
		(fp_line
			(start -0.12065 -0.2794)
			(end 0.12065 -0.2794)
			(stroke
				(width 0.1)
				(type default)
			)
			(layer "F.Fab")
		)
		(fp_line
			(start 0.12065 -0.2794)
			(end 0.12065 -0.3048)
			(stroke
				(width 0.1)
				(type default)
			)
			(layer "F.Fab")
		)
		(fp_line
			(start 0.12065 -0.3048)
			(end 0.67945 -0.3048)
			(stroke
				(width 0.1)
				(type default)
			)
			(layer "F.Fab")
		)
		(fp_line
			(start 0.67945 -0.3048)
			(end 0.67945 0.3048)
			(stroke
				(width 0.1)
				(type default)
			)
			(layer "F.Fab")
		)
		(fp_line
			(start -0.67945 -0.305054)
			(end -0.12065 -0.305054)
			(stroke
				(width 0.1)
				(type default)
			)
			(layer "F.Fab")
		)
		(fp_line
			(start -0.12065 -0.305054)
			(end -0.12065 -0.2794)
			(stroke
				(width 0.1)
				(type default)
			)
			(layer "F.Fab")
		)
		(pad "1" smd circle
			(at -0.40005 0 270)
			(size 0 0)
			(layers "F.Cu" "F.Mask" "F.Paste")
			(net "P3V3_AUX")
		)
		(pad "2" smd circle
			(at 0.40005 0 270)
			(size 0 0)
			(layers "F.Cu" "F.Mask" "F.Paste")
			(net "FM_BMC_DISABLE")
		)
	)
	(footprint ""
		(layer "F.Cu")
		(at 44.4754 -107.9246 -90)
		(property "Reference" "R483"
			(at 0 0 270)
			(layer "F.SilkS")
			(hide yes)
			(effects
				(font
					(size 1.27 1.27)
				)
			)
		)
		(property "Value" ""
			(at 0 0 270)
			(layer "F.Fab")
			(effects
				(font
					(size 1.27 1.27)
				)
			)
		)
		(duplicate_pad_numbers_are_jumpers no)
		(fp_line
			(start -0.7874 0.4064)
			(end -0.7874 -0.4064)
			(stroke
				(width 0.1524)
				(type default)
			)
			(layer "F.SilkS")
		)
		(fp_line
			(start 0.7874 0.4064)
			(end -0.7874 0.4064)
			(stroke
				(width 0.1524)
				(type default)
			)
			(layer "F.SilkS")
		)
		(fp_line
			(start -0.7874 -0.4064)
			(end 0.7874 -0.4064)
			(stroke
				(width 0.1524)
				(type default)
			)
			(layer "F.SilkS")
		)
		(fp_line
			(start 0.7874 -0.4064)
			(end 0.7874 0.4064)
			(stroke
				(width 0.1524)
				(type default)
			)
			(layer "F.SilkS")
		)
		(fp_line
			(start -0.67945 0.3048)
			(end -0.67945 -0.305054)
			(stroke
				(width 0.1)
				(type default)
			)
			(layer "F.Fab")
		)
		(fp_line
			(start -0.12065 0.3048)
			(end -0.67945 0.3048)
			(stroke
				(width 0.1)
				(type default)
			)
			(layer "F.Fab")
		)
		(fp_line
			(start 0.120396 0.3048)
			(end 0.120396 0.2794)
			(stroke
				(width 0.1)
				(type default)
			)
			(layer "F.Fab")
		)
		(fp_line
			(start 0.67945 0.3048)
			(end 0.120396 0.3048)
			(stroke
				(width 0.1)
				(type default)
			)
			(layer "F.Fab")
		)
		(fp_line
			(start -0.12065 0.2794)
			(end -0.12065 0.3048)
			(stroke
				(width 0.1)
				(type default)
			)
			(layer "F.Fab")
		)
		(fp_line
			(start 0.120396 0.2794)
			(end -0.12065 0.2794)
			(stroke
				(width 0.1)
				(type default)
			)
			(layer "F.Fab")
		)
		(fp_line
			(start -0.12065 -0.2794)
			(end 0.12065 -0.2794)
			(stroke
				(width 0.1)
				(type default)
			)
			(layer "F.Fab")
		)
		(fp_line
			(start 0.12065 -0.2794)
			(end 0.12065 -0.3048)
			(stroke
				(width 0.1)
				(type default)
			)
			(layer "F.Fab")
		)
		(fp_line
			(start 0.12065 -0.3048)
			(end 0.67945 -0.3048)
			(stroke
				(width 0.1)
				(type default)
			)
			(layer "F.Fab")
		)
		(fp_line
			(start 0.67945 -0.3048)
			(end 0.67945 0.3048)
			(stroke
				(width 0.1)
				(type default)
			)
			(layer "F.Fab")
		)
		(fp_line
			(start -0.67945 -0.305054)
			(end -0.12065 -0.305054)
			(stroke
				(width 0.1)
				(type default)
			)
			(layer "F.Fab")
		)
		(fp_line
			(start -0.12065 -0.305054)
			(end -0.12065 -0.2794)
			(stroke
				(width 0.1)
				(type default)
			)
			(layer "F.Fab")
		)
		(pad "1" smd circle
			(at -0.40005 0 270)
			(size 0 0)
			(layers "F.Cu" "F.Mask" "F.Paste")
			(net "SPI_PCH_MUXED_IO2")
		)
		(pad "2" smd circle
			(at 0.40005 0 270)
			(size 0 0)
			(layers "F.Cu" "F.Mask" "F.Paste")
			(net "SPI_PCH_IO2_FLASH_R1")
		)
	)
)
